# ZAIUS-LBB-EVT2-X01-BOM-X03-20161116.xls — TBD AVL Qual (bom)
| NOTES: |  |  |  |  |  |  |
| The following items are alternates to the items listed in the Critical Components Qual tab. |  |  |  |  |  |  |
| These components will be included on near future, non-customer builds for validation and approval by both Dell and the ODM. |  |  |  |  |  |  |
| Item Description | ODM P/N | Dell PN | Vendor | Vendor PN | Build ?? | Estimated Completion Date |
| SATA connectors (black) |  |  |  |  |  |  |
| -  Alternate |  |  |  |  |  |  |
| SATA connectors (blue) |  |  |  |  |  |  |
| -  Alternate |  |  |  |  |  |  |
| PCIe retention |  |  |  |  |  |  |
| -  Alternate |  |  |  |  |  |  |
| RTC XTAL |  |  |  |  |  |  |
| -  Alternate |  |  |  |  |  |  |
| XTAL |  |  |  |  |  |  |
| -  Alternate |  |  |  |  |  |  |
